# BASEBOARD_FAB2 (Tioga Pass) — schematic netlist excerpt (pin names and nets, part order shuffled) for the footprints in the layout excerpt that follows; sources: Cadence DE-HDL packaged netlist, KiCad conversion of Wiwynn_Tioga_Pass_MB.brd

R6W18  RES  0.0 5% CHIP  pkg 0402  page 145 : A = SMB_DEBUG_STBY_LVC3_SDA ; B = SMB_DEBUG_STBY_LVC3_SDA_R
R25W19  120R2F-GP  1%  pkg RCL_GP  page 151 : \1\ = GND ; \2\ = BMC_M_A7
C22W9  SC22U16V5MX-4-GP  20%  pkg SMD-BCG5  page 241 : \1\ = VR_FET_SW_P5V_STBY_PVIN ; \2\ = GND
C22W28  SC22U16V5MX-4-GP  20%  pkg SMD-BCG5  page 212 : \1\ = VR_FET_SW_P12V_STBY_PVCCIO_CPU0 ; \2\ = GND

(kicad_pcb
	(version 20260206)
	(generator "pcbnew")
	(generator_version "10.0")
	(general
		(thickness 1.6)
		(legacy_teardrops no)
	)
	(paper "A4")
	(title_block
		(title "Wiwynn_Tioga_Pass_MB.brd")
		(comment 1 "Tioga Pass / footprints 107-110 of 4770")
	)
	(layers
		(0 "F.Cu" signal "TOP")
		(4 "In1.Cu" signal "L2GND")
		(6 "In2.Cu" signal "L3")
		(8 "In3.Cu" signal "L4GND")
		(10 "In4.Cu" signal "L5")
		(12 "In5.Cu" signal "L6GND")
		(14 "In6.Cu" signal "L7VCC")
		(16 "In7.Cu" signal "L8VCC")
		(18 "In8.Cu" signal "L9GND")
		(20 "In9.Cu" signal "L10")
		(22 "In10.Cu" signal "L11GND")
		(24 "In11.Cu" signal "L12")
		(26 "In12.Cu" signal "L13GND")
		(2 "B.Cu" signal "BOTTOM")
		(9 "F.Adhes" user "F.Adhesive")
		(11 "B.Adhes" user "B.Adhesive")
		(13 "F.Paste" user "Package Geometry/Pastemask Top")
		(15 "B.Paste" user "Package Geometry/Pastemask Bottom")
		(5 "F.SilkS" user "Ref Des/Silkscreen Top")
		(7 "B.SilkS" user "Ref Des/Silkscreen Bottom")
		(1 "F.Mask" user "Board Geometry/Soldermask Top")
		(3 "B.Mask" user "Board Geometry/Soldermask Bottom")
		(17 "Dwgs.User" user "User.Drawings")
		(19 "Cmts.User" user "User.Comments")
		(21 "Eco1.User" user "User.Eco1")
		(23 "Eco2.User" user "User.Eco2")
		(25 "Edge.Cuts" user "Board Geometry/Outline")
		(27 "Margin" user)
		(31 "F.CrtYd" user "Package Geometry/Place Bound Top")
		(29 "B.CrtYd" user "Package Geometry/Place Bound Bottom")
		(35 "F.Fab" user "Ref Des/Assembly Top")
		(33 "B.Fab" user "Ref Des/Assembly Bottom")
	)
	(footprint ""
		(layer "F.Cu")
		(at 388.2263 -68.8848 180)
		(property "Reference" "C22W9"
			(at 0 0 180)
			(layer "F.SilkS")
			(hide yes)
			(effects
				(font
					(size 1.27 1.27)
				)
			)
		)
		(property "Value" "*"
			(at -0.0762 -6.2357 180)
			(unlocked yes)
			(layer "F.Fab")
			(hide yes)
			(effects
				(font
					(size 1.27 1.016)
					(thickness 0.1524)
				)
			)
		)
		(property "Device Type" "SC22U16V5MX-4-GP_SMD-BCG5-SC22A"
			(at -0.0762 -8.2677 180)
			(unlocked yes)
			(layer "F.Fab")
			(hide yes)
			(effects
				(font
					(size 1.27 1.016)
					(thickness 0.1524)
				)
			)
		)
		(duplicate_pad_numbers_are_jumpers no)
		(fp_line
			(start 0.635 0)
			(end -0.635 0)
			(stroke
				(width 0.508)
				(type default)
			)
			(layer "F.SilkS")
		)
		(fp_rect
			(start -0.9652 1.778)
			(end 0.9652 -1.778)
			(stroke
				(width 0)
				(type default)
			)
			(fill no)
			(layer "F.CrtYd")
		)
		(fp_poly
			(pts
				(xy -0.9652 -1.778) (xy 0.9652 -1.778) (xy 0.9652 1.778) (xy -0.9652 1.778)
			)
			(stroke
				(width 0)
				(type default)
			)
			(fill no)
			(layer "F.Fab")
		)
		(pad "1" smd rect
			(at 0 -0.9652 180)
			(size 1.397 1.143)
			(layers "F.Cu" "F.Mask" "F.Paste")
			(net "VR_FET_SW_P5V_STBY_PVIN")
		)
		(pad "2" smd rect
			(at 0 0.9652 180)
			(size 1.397 1.143)
			(layers "F.Cu" "F.Mask" "F.Paste")
			(net "GND")
		)
	)
	(footprint ""
		(layer "F.Cu")
		(at 348.488 -104.267 180)
		(property "Reference" "C22W28"
			(at 0 0 180)
			(layer "F.SilkS")
			(hide yes)
			(effects
				(font
					(size 1.27 1.27)
				)
			)
		)
		(property "Value" "*"
			(at -0.0762 -6.2357 180)
			(unlocked yes)
			(layer "F.Fab")
			(hide yes)
			(effects
				(font
					(size 1.27 1.016)
					(thickness 0.1524)
				)
			)
		)
		(property "Device Type" "SC22U16V5MX-4-GP_SMD-BCG5-SC22A"
			(at -0.0762 -8.2677 180)
			(unlocked yes)
			(layer "F.Fab")
			(hide yes)
			(effects
				(font
					(size 1.27 1.016)
					(thickness 0.1524)
				)
			)
		)
		(duplicate_pad_numbers_are_jumpers no)
		(fp_line
			(start 0.635 0)
			(end -0.635 0)
			(stroke
				(width 0.508)
				(type default)
			)
			(layer "F.SilkS")
		)
		(fp_rect
			(start -0.9652 1.778)
			(end 0.9652 -1.778)
			(stroke
				(width 0)
				(type default)
			)
			(fill no)
			(layer "F.CrtYd")
		)
		(fp_poly
			(pts
				(xy -0.9652 -1.778) (xy 0.9652 -1.778) (xy 0.9652 1.778) (xy -0.9652 1.778)
			)
			(stroke
				(width 0)
				(type default)
			)
			(fill no)
			(layer "F.Fab")
		)
		(pad "1" smd rect
			(at 0 -0.9652 180)
			(size 1.397 1.143)
			(layers "F.Cu" "F.Mask" "F.Paste")
			(net "VR_FET_SW_P12V_STBY_PVCCIO_CPU0")
		)
		(pad "2" smd rect
			(at 0 0.9652 180)
			(size 1.397 1.143)
			(layers "F.Cu" "F.Mask" "F.Paste")
			(net "GND")
		)
	)
	(footprint ""
		(layer "F.Cu")
		(at 401.472146 -36.458652 90)
		(property "Reference" "R6W18"
			(at -0.8382 -0.67818 90)
			(unlocked yes)
			(layer "F.SilkS")
			(effects
				(font
					(size 0.4064 0.254)
					(thickness 0.1524)
				)
				(justify left)
			)
		)
		(property "Value" ""
			(at 0 0 90)
			(layer "F.Fab")
			(effects
				(font
					(size 1.27 1.27)
				)
			)
		)
		(duplicate_pad_numbers_are_jumpers no)
		(fp_poly
			(pts
				(xy -0.2794 -0.1016) (xy 0.2794 -0.1016) (xy 0.2794 0.9906) (xy -0.2794 0.9906)
			)
			(stroke
				(width 0)
				(type default)
			)
			(fill no)
			(layer "F.CrtYd")
		)
		(fp_line
			(start 0.2794 -0.1016)
			(end -0.2794 -0.1016)
			(stroke
				(width 0.1)
				(type default)
			)
			(layer "F.Fab")
		)
		(fp_line
			(start -0.2794 -0.1016)
			(end -0.2794 0.9906)
			(stroke
				(width 0.1)
				(type default)
			)
			(layer "F.Fab")
		)
		(fp_line
			(start 0.2794 0.9906)
			(end 0.2794 -0.1016)
			(stroke
				(width 0.1)
				(type default)
			)
			(layer "F.Fab")
		)
		(fp_line
			(start -0.2794 0.9906)
			(end 0.2794 0.9906)
			(stroke
				(width 0.1)
				(type default)
			)
			(layer "F.Fab")
		)
		(pad "1" smd rect
			(at 0 0 90)
			(size 0.508 0.508)
			(layers "F.Cu" "F.Mask" "F.Paste")
			(net "SMB_DEBUG_STBY_LVC3_SDA")
		)
		(pad "2" smd rect
			(at 0 0.889 90)
			(size 0.508 0.508)
			(layers "F.Cu" "F.Mask" "F.Paste")
			(net "SMB_DEBUG_STBY_LVC3_SDA_R")
		)
		(zone
			(layer "F.Cu")
			(hatch none 0.5)
			(connect_pads
				(clearance 0)
			)
			(min_thickness 0.25)
			(keepout
				(tracks allowed)
				(vias not_allowed)
				(pads allowed)
				(copperpour not_allowed)
				(footprints allowed)
			)
			(placement
				(enabled no)
				(sheetname "")
			)
			(fill
				(thermal_gap 0.5)
				(thermal_bridge_width 0.5)
				(island_removal_mode 0)
			)
			(polygon
				(pts
					(xy 401.726146 -36.204652) (xy 401.726146 -36.712652) (xy 402.107146 -36.712652) (xy 402.107146 -36.204652)
				)
			)
		)
		(zone
			(layer "F.Cu")
			(hatch none 0.5)
			(connect_pads
				(clearance 0)
			)
			(min_thickness 0.25)
			(keepout
				(tracks not_allowed)
				(vias allowed)
				(pads allowed)
				(copperpour not_allowed)
				(footprints allowed)
			)
			(placement
				(enabled no)
				(sheetname "")
			)
			(fill
				(thermal_gap 0.5)
				(thermal_bridge_width 0.5)
				(island_removal_mode 0)
			)
			(polygon
				(pts
					(xy 402.107146 -36.204652) (xy 402.107146 -36.712652) (xy 401.726146 -36.712652) (xy 401.726146 -36.204652)
				)
			)
		)
	)
	(footprint ""
		(layer "F.Cu")
		(at 436.547006 -41.663874 180)
		(property "Reference" "R25W19"
			(at 0 0 180)
			(layer "F.SilkS")
			(hide yes)
			(effects
				(font
					(size 1.27 1.27)
				)
			)
		)
		(property "Value" "*"
			(at 0.064008 -4.108196 180)
			(unlocked yes)
			(layer "F.Fab")
			(hide yes)
			(effects
				(font
					(size 1.27 1.016)
					(thickness 0.1524)
				)
			)
		)
		(property "Device Type" "120R2F-GP_RCL_GP-120R2F-GP,64.A"
			(at 0.064008 -5.632196 180)
			(unlocked yes)
			(layer "F.Fab")
			(hide yes)
			(effects
				(font
					(size 1.27 1.016)
					(thickness 0.1524)
				)
			)
		)
		(duplicate_pad_numbers_are_jumpers no)
		(fp_line
			(start 0.508 -0.9398)
			(end -0.508 -0.9398)
			(stroke
				(width 0.1524)
				(type default)
			)
			(layer "F.SilkS")
		)
		(fp_line
			(start -0.508 -0.9398)
			(end -0.508 0.9398)
			(stroke
				(width 0.1524)
				(type default)
			)
			(layer "F.SilkS")
		)
		(fp_rect
			(start -0.508 0.9398)
			(end 0.508 -0.9398)
			(stroke
				(width 0)
				(type default)
			)
			(fill no)
			(layer "F.CrtYd")
		)
		(fp_rect
			(start -0.508 0.9398)
			(end 0.508 -0.9398)
			(stroke
				(width 0)
				(type default)
			)
			(fill no)
			(layer "F.Fab")
		)
		(pad "1" smd custom
			(at 0 -0.4445 180)
			(size 0.1397 0.1397)
			(layers "F.Cu" "F.Mask" "F.Paste")
			(net "GND")
			(options
				(clearance outline)
				(anchor circle)
			)
			(primitives
				(gr_poly
					(pts
						(arc
							(start -0.1778 -0.2794)
							(mid -0.249642 -0.249642)
							(end -0.2794 -0.1778)
						)
						(arc
							(start -0.2794 0.1778)
							(mid -0.249642 0.249642)
							(end -0.1778 0.2794)
						)
						(arc
							(start 0.1778 0.2794)
							(mid 0.249642 0.249642)
							(end 0.2794 0.1778)
						)
						(arc
							(start 0.2794 -0.1778)
							(mid 0.249642 -0.249642)
							(end 0.1778 -0.2794)
						)
					)
					(width 0)
					(fill yes)
				)
			)
		)
		(pad "2" smd custom
			(at 0 0.4445 180)
			(size 0.1397 0.1397)
			(layers "F.Cu" "F.Mask" "F.Paste")
			(net "BMC_M_A7")
			(options
				(clearance outline)
				(anchor circle)
			)
			(primitives
				(gr_poly
					(pts
						(arc
							(start -0.1778 -0.2794)
							(mid -0.249642 -0.249642)
							(end -0.2794 -0.1778)
						)
						(arc
							(start -0.2794 0.1778)
							(mid -0.249642 0.249642)
							(end -0.1778 0.2794)
						)
						(arc
							(start 0.1778 0.2794)
							(mid 0.249642 0.249642)
							(end 0.2794 0.1778)
						)
						(arc
							(start 0.2794 -0.1778)
							(mid 0.249642 -0.249642)
							(end 0.1778 -0.2794)
						)
					)
					(width 0)
					(fill yes)
				)
			)
		)
	)
)
